(kicad_pcb
	(version 20260206)
	(generator "pcbnew")
	(generator_version "10.0")
	(general
		(thickness 1.6)
		(legacy_teardrops no)
	)
	(paper "A4")
	(title_block
		(title "01162023_DA0F0TEBIF0_F0T_Expander_BD_F_brd_V02_OCP.brd")
		(comment 1 "Grand Teton / footprints 974-979 of 9728")
	)
	(layers
		(0 "F.Cu" signal "TOP")
		(4 "In1.Cu" signal "GND")
		(6 "In2.Cu" signal "VCC")
		(8 "In3.Cu" signal "VCC1")
		(10 "In4.Cu" signal "GND1")
		(12 "In5.Cu" signal "IN1")
		(14 "In6.Cu" signal "GND2")
		(16 "In7.Cu" signal "IN2")
		(18 "In8.Cu" signal "GND3")
		(20 "In9.Cu" signal "IN3")
		(22 "In10.Cu" signal "GND4")
		(24 "In11.Cu" signal "IN4")
		(26 "In12.Cu" signal "GND5")
		(28 "In13.Cu" signal "IN5")
		(30 "In14.Cu" signal "GND6")
		(32 "In15.Cu" signal "IN6")
		(34 "In16.Cu" signal "GND7")
		(2 "B.Cu" signal "BOTTOM")
		(9 "F.Adhes" user "F.Adhesive")
		(11 "B.Adhes" user "B.Adhesive")
		(13 "F.Paste" user "Package Geometry/Pastemask Top")
		(15 "B.Paste" user "Package Geometry/Pastemask Bottom")
		(5 "F.SilkS" user "Ref Des/Silkscreen Top")
		(7 "B.SilkS" user "Ref Des/Silkscreen Bottom")
		(1 "F.Mask" user "Board Geometry/Soldermask Top")
		(3 "B.Mask" user "Board Geometry/Soldermask Bottom")
		(17 "Dwgs.User" user "User.Drawings")
		(19 "Cmts.User" user "User.Comments")
		(21 "Eco1.User" user "User.Eco1")
		(23 "Eco2.User" user "User.Eco2")
		(25 "Edge.Cuts" user "Board Geometry/Outline")
		(27 "Margin" user)
		(31 "F.CrtYd" user "Package Geometry/Place Bound Top")
		(29 "B.CrtYd" user "Package Geometry/Place Bound Bottom")
		(35 "F.Fab" user "Ref Des/Assembly Top")
		(33 "B.Fab" user "Ref Des/Assembly Bottom")
	)
	(footprint ""
		(layer "F.Cu")
		(at 149.954234 -307.415438 45)
		(property "Reference" "R1285"
			(at 0 0 45)
			(layer "F.SilkS")
			(hide yes)
			(effects
				(font
					(size 1.27 1.27)
				)
			)
		)
		(property "Value" ""
			(at 0 0 45)
			(layer "F.Fab")
			(effects
				(font
					(size 1.27 1.27)
				)
			)
		)
		(duplicate_pad_numbers_are_jumpers no)
		(fp_line
			(start -0.787389 -0.406267)
			(end 0.787389 -0.406267)
			(stroke
				(width 0.1524)
				(type default)
			)
			(layer "F.SilkS")
		)
		(fp_line
			(start -0.787389 0.406267)
			(end -0.787389 -0.406267)
			(stroke
				(width 0.1524)
				(type default)
			)
			(layer "F.SilkS")
		)
		(fp_line
			(start 0.787389 -0.406267)
			(end 0.787389 0.406267)
			(stroke
				(width 0.1524)
				(type default)
			)
			(layer "F.SilkS")
		)
		(fp_line
			(start 0.787389 0.406267)
			(end -0.787389 0.406267)
			(stroke
				(width 0.1524)
				(type default)
			)
			(layer "F.SilkS")
		)
		(fp_line
			(start -0.679446 -0.305149)
			(end -0.120695 -0.304969)
			(stroke
				(width 0.1)
				(type default)
			)
			(layer "F.Fab")
		)
		(fp_line
			(start -0.120695 -0.304969)
			(end -0.120695 -0.279466)
			(stroke
				(width 0.1)
				(type default)
			)
			(layer "F.Fab")
		)
		(fp_line
			(start -0.120695 -0.279466)
			(end 0.120695 -0.279466)
			(stroke
				(width 0.1)
				(type default)
			)
			(layer "F.Fab")
		)
		(fp_line
			(start -0.679446 0.30479)
			(end -0.679446 -0.305149)
			(stroke
				(width 0.1)
				(type default)
			)
			(layer "F.Fab")
		)
		(fp_line
			(start 0.120515 -0.30479)
			(end 0.679446 -0.30479)
			(stroke
				(width 0.1)
				(type default)
			)
			(layer "F.Fab")
		)
		(fp_line
			(start 0.120695 -0.279466)
			(end 0.120515 -0.30479)
			(stroke
				(width 0.1)
				(type default)
			)
			(layer "F.Fab")
		)
		(fp_line
			(start -0.120695 0.279466)
			(end -0.120515 0.30479)
			(stroke
				(width 0.1)
				(type default)
			)
			(layer "F.Fab")
		)
		(fp_line
			(start -0.120515 0.30479)
			(end -0.679446 0.30479)
			(stroke
				(width 0.1)
				(type default)
			)
			(layer "F.Fab")
		)
		(fp_line
			(start 0.679446 -0.30479)
			(end 0.679446 0.30479)
			(stroke
				(width 0.1)
				(type default)
			)
			(layer "F.Fab")
		)
		(fp_line
			(start 0.120335 0.279466)
			(end -0.120695 0.279466)
			(stroke
				(width 0.1)
				(type default)
			)
			(layer "F.Fab")
		)
		(fp_line
			(start 0.120515 0.30479)
			(end 0.120335 0.279466)
			(stroke
				(width 0.1)
				(type default)
			)
			(layer "F.Fab")
		)
		(fp_line
			(start 0.679446 0.30479)
			(end 0.120515 0.30479)
			(stroke
				(width 0.1)
				(type default)
			)
			(layer "F.Fab")
		)
		(pad "1" smd circle
			(at -0.40005 0 45)
			(size 0 0)
			(layers "F.Cu" "F.Mask" "F.Paste")
			(net "GND")
		)
		(pad "2" smd circle
			(at 0.40005 0 45)
			(size 0 0)
			(layers "F.Cu" "F.Mask" "F.Paste")
			(net "PEX1_DBG_MODE1")
		)
	)
	(footprint ""
		(layer "F.Cu")
		(at 90.915744 -309.760366 135)
		(property "Reference" "R1251"
			(at 0 0 135)
			(layer "F.SilkS")
			(hide yes)
			(effects
				(font
					(size 1.27 1.27)
				)
			)
		)
		(property "Value" ""
			(at 0 0 135)
			(layer "F.Fab")
			(effects
				(font
					(size 1.27 1.27)
				)
			)
		)
		(duplicate_pad_numbers_are_jumpers no)
		(fp_line
			(start 0.787389 -0.406267)
			(end 0.787389 0.406267)
			(stroke
				(width 0.1524)
				(type default)
			)
			(layer "F.SilkS")
		)
		(fp_line
			(start 0.787389 0.406267)
			(end -0.787389 0.406267)
			(stroke
				(width 0.1524)
				(type default)
			)
			(layer "F.SilkS")
		)
		(fp_line
			(start -0.787389 -0.406267)
			(end 0.787389 -0.406267)
			(stroke
				(width 0.1524)
				(type default)
			)
			(layer "F.SilkS")
		)
		(fp_line
			(start -0.787389 0.406267)
			(end -0.787389 -0.406267)
			(stroke
				(width 0.1524)
				(type default)
			)
			(layer "F.SilkS")
		)
		(fp_line
			(start 0.679446 -0.30479)
			(end 0.679446 0.30479)
			(stroke
				(width 0.1)
				(type default)
			)
			(layer "F.Fab")
		)
		(fp_line
			(start 0.120515 -0.30479)
			(end 0.679446 -0.30479)
			(stroke
				(width 0.1)
				(type default)
			)
			(layer "F.Fab")
		)
		(fp_line
			(start 0.120695 -0.279466)
			(end 0.120515 -0.30479)
			(stroke
				(width 0.1)
				(type default)
			)
			(layer "F.Fab")
		)
		(fp_line
			(start 0.679446 0.30479)
			(end 0.120515 0.30479)
			(stroke
				(width 0.1)
				(type default)
			)
			(layer "F.Fab")
		)
		(fp_line
			(start -0.120695 -0.304969)
			(end -0.120695 -0.279466)
			(stroke
				(width 0.1)
				(type default)
			)
			(layer "F.Fab")
		)
		(fp_line
			(start -0.120695 -0.279466)
			(end 0.120695 -0.279466)
			(stroke
				(width 0.1)
				(type default)
			)
			(layer "F.Fab")
		)
		(fp_line
			(start 0.120335 0.279466)
			(end -0.120695 0.279466)
			(stroke
				(width 0.1)
				(type default)
			)
			(layer "F.Fab")
		)
		(fp_line
			(start 0.120515 0.30479)
			(end 0.120335 0.279466)
			(stroke
				(width 0.1)
				(type default)
			)
			(layer "F.Fab")
		)
		(fp_line
			(start -0.679446 -0.305149)
			(end -0.120695 -0.304969)
			(stroke
				(width 0.1)
				(type default)
			)
			(layer "F.Fab")
		)
		(fp_line
			(start -0.120695 0.279466)
			(end -0.120515 0.30479)
			(stroke
				(width 0.1)
				(type default)
			)
			(layer "F.Fab")
		)
		(fp_line
			(start -0.120515 0.30479)
			(end -0.679446 0.30479)
			(stroke
				(width 0.1)
				(type default)
			)
			(layer "F.Fab")
		)
		(fp_line
			(start -0.679446 0.30479)
			(end -0.679446 -0.305149)
			(stroke
				(width 0.1)
				(type default)
			)
			(layer "F.Fab")
		)
		(pad "1" smd circle
			(at -0.40005 0 135)
			(size 0 0)
			(layers "F.Cu" "F.Mask" "F.Paste")
			(net "GND")
		)
		(pad "2" smd circle
			(at 0.40005 0 135)
			(size 0 0)
			(layers "F.Cu" "F.Mask" "F.Paste")
			(net "PEX0_SPARE0")
		)
	)
	(footprint ""
		(layer "F.Cu")
		(at 110.562898 -284.834838 90)
		(property "Reference" "PC76"
			(at 0 0 90)
			(layer "F.SilkS")
			(hide yes)
			(effects
				(font
					(size 1.27 1.27)
				)
			)
		)
		(property "Value" ""
			(at 0 0 90)
			(layer "F.Fab")
			(effects
				(font
					(size 1.27 1.27)
				)
			)
		)
		(duplicate_pad_numbers_are_jumpers no)
		(fp_line
			(start 0.7874 -0.4064)
			(end 0.7874 0.4064)
			(stroke
				(width 0.1524)
				(type default)
			)
			(layer "F.SilkS")
		)
		(fp_line
			(start -0.7874 -0.4064)
			(end 0.7874 -0.4064)
			(stroke
				(width 0.1524)
				(type default)
			)
			(layer "F.SilkS")
		)
		(fp_line
			(start 0.7874 0.4064)
			(end -0.7874 0.4064)
			(stroke
				(width 0.1524)
				(type default)
			)
			(layer "F.SilkS")
		)
		(fp_line
			(start -0.7874 0.4064)
			(end -0.7874 -0.4064)
			(stroke
				(width 0.1524)
				(type default)
			)
			(layer "F.SilkS")
		)
		(fp_line
			(start -0.12065 -0.305054)
			(end -0.12065 -0.2794)
			(stroke
				(width 0.1)
				(type default)
			)
			(layer "F.Fab")
		)
		(fp_line
			(start -0.67945 -0.305054)
			(end -0.12065 -0.305054)
			(stroke
				(width 0.1)
				(type default)
			)
			(layer "F.Fab")
		)
		(fp_line
			(start 0.67945 -0.3048)
			(end 0.67945 0.3048)
			(stroke
				(width 0.1)
				(type default)
			)
			(layer "F.Fab")
		)
		(fp_line
			(start 0.12065 -0.3048)
			(end 0.67945 -0.3048)
			(stroke
				(width 0.1)
				(type default)
			)
			(layer "F.Fab")
		)
		(fp_line
			(start 0.12065 -0.2794)
			(end 0.12065 -0.3048)
			(stroke
				(width 0.1)
				(type default)
			)
			(layer "F.Fab")
		)
		(fp_line
			(start -0.12065 -0.2794)
			(end 0.12065 -0.2794)
			(stroke
				(width 0.1)
				(type default)
			)
			(layer "F.Fab")
		)
		(fp_line
			(start 0.120396 0.2794)
			(end -0.12065 0.2794)
			(stroke
				(width 0.1)
				(type default)
			)
			(layer "F.Fab")
		)
		(fp_line
			(start -0.12065 0.2794)
			(end -0.12065 0.3048)
			(stroke
				(width 0.1)
				(type default)
			)
			(layer "F.Fab")
		)
		(fp_line
			(start 0.67945 0.3048)
			(end 0.120396 0.3048)
			(stroke
				(width 0.1)
				(type default)
			)
			(layer "F.Fab")
		)
		(fp_line
			(start 0.120396 0.3048)
			(end 0.120396 0.2794)
			(stroke
				(width 0.1)
				(type default)
			)
			(layer "F.Fab")
		)
		(fp_line
			(start -0.12065 0.3048)
			(end -0.67945 0.3048)
			(stroke
				(width 0.1)
				(type default)
			)
			(layer "F.Fab")
		)
		(fp_line
			(start -0.67945 0.3048)
			(end -0.67945 -0.305054)
			(stroke
				(width 0.1)
				(type default)
			)
			(layer "F.Fab")
		)
		(pad "1" smd circle
			(at -0.40005 0 90)
			(size 0 0)
			(layers "F.Cu" "F.Mask" "F.Paste")
			(net "SW_P12V_P0V8_PEX0_FLT")
		)
		(pad "2" smd circle
			(at 0.40005 0 90)
			(size 0 0)
			(layers "F.Cu" "F.Mask" "F.Paste")
			(net "GND")
		)
	)
	(footprint ""
		(layer "F.Cu")
		(at 358.417876 -398.178528 -90)
		(property "Reference" "R6704"
			(at 0 0 270)
			(layer "F.SilkS")
			(hide yes)
			(effects
				(font
					(size 1.27 1.27)
				)
			)
		)
		(property "Value" ""
			(at 0 0 270)
			(layer "F.Fab")
			(effects
				(font
					(size 1.27 1.27)
				)
			)
		)
		(duplicate_pad_numbers_are_jumpers no)
		(fp_line
			(start -0.7874 0.4064)
			(end -0.7874 -0.4064)
			(stroke
				(width 0.1524)
				(type default)
			)
			(layer "F.SilkS")
		)
		(fp_line
			(start 0.7874 0.4064)
			(end -0.7874 0.4064)
			(stroke
				(width 0.1524)
				(type default)
			)
			(layer "F.SilkS")
		)
		(fp_line
			(start -0.7874 -0.4064)
			(end 0.7874 -0.4064)
			(stroke
				(width 0.1524)
				(type default)
			)
			(layer "F.SilkS")
		)
		(fp_line
			(start 0.7874 -0.4064)
			(end 0.7874 0.4064)
			(stroke
				(width 0.1524)
				(type default)
			)
			(layer "F.SilkS")
		)
		(fp_line
			(start -0.67945 0.3048)
			(end -0.67945 -0.305054)
			(stroke
				(width 0.1)
				(type default)
			)
			(layer "F.Fab")
		)
		(fp_line
			(start -0.12065 0.3048)
			(end -0.67945 0.3048)
			(stroke
				(width 0.1)
				(type default)
			)
			(layer "F.Fab")
		)
		(fp_line
			(start 0.120396 0.3048)
			(end 0.120396 0.2794)
			(stroke
				(width 0.1)
				(type default)
			)
			(layer "F.Fab")
		)
		(fp_line
			(start 0.67945 0.3048)
			(end 0.120396 0.3048)
			(stroke
				(width 0.1)
				(type default)
			)
			(layer "F.Fab")
		)
		(fp_line
			(start -0.12065 0.2794)
			(end -0.12065 0.3048)
			(stroke
				(width 0.1)
				(type default)
			)
			(layer "F.Fab")
		)
		(fp_line
			(start 0.120396 0.2794)
			(end -0.12065 0.2794)
			(stroke
				(width 0.1)
				(type default)
			)
			(layer "F.Fab")
		)
		(fp_line
			(start -0.12065 -0.2794)
			(end 0.12065 -0.2794)
			(stroke
				(width 0.1)
				(type default)
			)
			(layer "F.Fab")
		)
		(fp_line
			(start 0.12065 -0.2794)
			(end 0.12065 -0.3048)
			(stroke
				(width 0.1)
				(type default)
			)
			(layer "F.Fab")
		)
		(fp_line
			(start 0.12065 -0.3048)
			(end 0.67945 -0.3048)
			(stroke
				(width 0.1)
				(type default)
			)
			(layer "F.Fab")
		)
		(fp_line
			(start 0.67945 -0.3048)
			(end 0.67945 0.3048)
			(stroke
				(width 0.1)
				(type default)
			)
			(layer "F.Fab")
		)
		(fp_line
			(start -0.67945 -0.305054)
			(end -0.12065 -0.305054)
			(stroke
				(width 0.1)
				(type default)
			)
			(layer "F.Fab")
		)
		(fp_line
			(start -0.12065 -0.305054)
			(end -0.12065 -0.2794)
			(stroke
				(width 0.1)
				(type default)
			)
			(layer "F.Fab")
		)
		(pad "1" smd circle
			(at -0.40005 0 270)
			(size 0 0)
			(layers "F.Cu" "F.Mask" "F.Paste")
			(net "MB_3V3IO_RSVD3_ISO_R")
		)
		(pad "2" smd circle
			(at 0.40005 0 270)
			(size 0 0)
			(layers "F.Cu" "F.Mask" "F.Paste")
			(net "MB_3V3IO_RSVD3_ISO")
		)
	)
	(footprint ""
		(layer "F.Cu")
		(at 350.647 -185.42 90)
		(property "Reference" "C3601"
			(at 0 0 90)
			(layer "F.SilkS")
			(hide yes)
			(effects
				(font
					(size 1.27 1.27)
				)
			)
		)
		(property "Value" ""
			(at 0 0 90)
			(layer "F.Fab")
			(effects
				(font
					(size 1.27 1.27)
				)
			)
		)
		(duplicate_pad_numbers_are_jumpers no)
		(fp_line
			(start 0.7874 -0.4064)
			(end 0.7874 0.4064)
			(stroke
				(width 0.1524)
				(type default)
			)
			(layer "F.SilkS")
		)
		(fp_line
			(start -0.7874 -0.4064)
			(end 0.7874 -0.4064)
			(stroke
				(width 0.1524)
				(type default)
			)
			(layer "F.SilkS")
		)
		(fp_line
			(start 0.7874 0.4064)
			(end -0.7874 0.4064)
			(stroke
				(width 0.1524)
				(type default)
			)
			(layer "F.SilkS")
		)
		(fp_line
			(start -0.7874 0.4064)
			(end -0.7874 -0.4064)
			(stroke
				(width 0.1524)
				(type default)
			)
			(layer "F.SilkS")
		)
		(fp_line
			(start -0.12065 -0.305054)
			(end -0.12065 -0.2794)
			(stroke
				(width 0.1)
				(type default)
			)
			(layer "F.Fab")
		)
		(fp_line
			(start -0.67945 -0.305054)
			(end -0.12065 -0.305054)
			(stroke
				(width 0.1)
				(type default)
			)
			(layer "F.Fab")
		)
		(fp_line
			(start 0.67945 -0.3048)
			(end 0.67945 0.3048)
			(stroke
				(width 0.1)
				(type default)
			)
			(layer "F.Fab")
		)
		(fp_line
			(start 0.12065 -0.3048)
			(end 0.67945 -0.3048)
			(stroke
				(width 0.1)
				(type default)
			)
			(layer "F.Fab")
		)
		(fp_line
			(start 0.12065 -0.2794)
			(end 0.12065 -0.3048)
			(stroke
				(width 0.1)
				(type default)
			)
			(layer "F.Fab")
		)
		(fp_line
			(start -0.12065 -0.2794)
			(end 0.12065 -0.2794)
			(stroke
				(width 0.1)
				(type default)
			)
			(layer "F.Fab")
		)
		(fp_line
			(start 0.120396 0.2794)
			(end -0.12065 0.2794)
			(stroke
				(width 0.1)
				(type default)
			)
			(layer "F.Fab")
		)
		(fp_line
			(start -0.12065 0.2794)
			(end -0.12065 0.3048)
			(stroke
				(width 0.1)
				(type default)
			)
			(layer "F.Fab")
		)
		(fp_line
			(start 0.67945 0.3048)
			(end 0.120396 0.3048)
			(stroke
				(width 0.1)
				(type default)
			)
			(layer "F.Fab")
		)
		(fp_line
			(start 0.120396 0.3048)
			(end 0.120396 0.2794)
			(stroke
				(width 0.1)
				(type default)
			)
			(layer "F.Fab")
		)
		(fp_line
			(start -0.12065 0.3048)
			(end -0.67945 0.3048)
			(stroke
				(width 0.1)
				(type default)
			)
			(layer "F.Fab")
		)
		(fp_line
			(start -0.67945 0.3048)
			(end -0.67945 -0.305054)
			(stroke
				(width 0.1)
				(type default)
			)
			(layer "F.Fab")
		)
		(pad "1" smd circle
			(at -0.40005 0 90)
			(size 0 0)
			(layers "F.Cu" "F.Mask" "F.Paste")
			(net "P3V3_AUX")
		)
		(pad "2" smd circle
			(at 0.40005 0 90)
			(size 0 0)
			(layers "F.Cu" "F.Mask" "F.Paste")
			(net "GND")
		)
	)
	(footprint ""
		(layer "F.Cu")
		(at 396.185644 -25.1587 -90)
		(property "Reference" "R5754"
			(at 0 0 270)
			(layer "F.SilkS")
			(hide yes)
			(effects
				(font
					(size 1.27 1.27)
				)
			)
		)
		(property "Value" ""
			(at 0 0 270)
			(layer "F.Fab")
			(effects
				(font
					(size 1.27 1.27)
				)
			)
		)
		(duplicate_pad_numbers_are_jumpers no)
		(fp_line
			(start -0.7874 0.4064)
			(end -0.7874 -0.4064)
			(stroke
				(width 0.1524)
				(type default)
			)
			(layer "F.SilkS")
		)
		(fp_line
			(start 0.7874 0.4064)
			(end -0.7874 0.4064)
			(stroke
				(width 0.1524)
				(type default)
			)
			(layer "F.SilkS")
		)
		(fp_line
			(start -0.7874 -0.4064)
			(end 0.7874 -0.4064)
			(stroke
				(width 0.1524)
				(type default)
			)
			(layer "F.SilkS")
		)
		(fp_line
			(start 0.7874 -0.4064)
			(end 0.7874 0.4064)
			(stroke
				(width 0.1524)
				(type default)
			)
			(layer "F.SilkS")
		)
		(fp_line
			(start -0.67945 0.3048)
			(end -0.67945 -0.305054)
			(stroke
				(width 0.1)
				(type default)
			)
			(layer "F.Fab")
		)
		(fp_line
			(start -0.12065 0.3048)
			(end -0.67945 0.3048)
			(stroke
				(width 0.1)
				(type default)
			)
			(layer "F.Fab")
		)
		(fp_line
			(start 0.120396 0.3048)
			(end 0.120396 0.2794)
			(stroke
				(width 0.1)
				(type default)
			)
			(layer "F.Fab")
		)
		(fp_line
			(start 0.67945 0.3048)
			(end 0.120396 0.3048)
			(stroke
				(width 0.1)
				(type default)
			)
			(layer "F.Fab")
		)
		(fp_line
			(start -0.12065 0.2794)
			(end -0.12065 0.3048)
			(stroke
				(width 0.1)
				(type default)
			)
			(layer "F.Fab")
		)
		(fp_line
			(start 0.120396 0.2794)
			(end -0.12065 0.2794)
			(stroke
				(width 0.1)
				(type default)
			)
			(layer "F.Fab")
		)
		(fp_line
			(start -0.12065 -0.2794)
			(end 0.12065 -0.2794)
			(stroke
				(width 0.1)
				(type default)
			)
			(layer "F.Fab")
		)
		(fp_line
			(start 0.12065 -0.2794)
			(end 0.12065 -0.3048)
			(stroke
				(width 0.1)
				(type default)
			)
			(layer "F.Fab")
		)
		(fp_line
			(start 0.12065 -0.3048)
			(end 0.67945 -0.3048)
			(stroke
				(width 0.1)
				(type default)
			)
			(layer "F.Fab")
		)
		(fp_line
			(start 0.67945 -0.3048)
			(end 0.67945 0.3048)
			(stroke
				(width 0.1)
				(type default)
			)
			(layer "F.Fab")
		)
		(fp_line
			(start -0.67945 -0.305054)
			(end -0.12065 -0.305054)
			(stroke
				(width 0.1)
				(type default)
			)
			(layer "F.Fab")
		)
		(fp_line
			(start -0.12065 -0.305054)
			(end -0.12065 -0.2794)
			(stroke
				(width 0.1)
				(type default)
			)
			(layer "F.Fab")
		)
		(pad "1" smd circle
			(at -0.40005 0 270)
			(size 0 0)
			(layers "F.Cu" "F.Mask" "F.Paste")
			(net "SSD13_LED_ISO_N")
		)
		(pad "2" smd circle
			(at 0.40005 0 270)
			(size 0 0)
			(layers "F.Cu" "F.Mask" "F.Paste")
			(net "SSD13_LED_ISO_R_N")
		)
	)
)
